# S9S_MB_2U (Grand Teton) — schematic netlist excerpt (pin names and nets, part order shuffled) for the footprints in the layout excerpt that follows; sources: Cadence DE-HDL packaged netlist, KiCad conversion of 03242023_DA0F0TMBIJ0_F0T_Motherboard_J_brd_V01_OCP.brd

C1187  Q_CAP  22UF 4V 20% X6S  pkg C0603  page 189 : A = P1V05_PCH_AUX ; B = GND
R1744  Q_RES  0 5% CHIP  pkg 0402LF  page 223 : A = FM_BMC_PWRBTN_OUT_N ; B = FM_BMC_PWRBTN_N

(kicad_pcb
	(version 20260206)
	(generator "pcbnew")
	(generator_version "10.0")
	(general
		(thickness 1.6)
		(legacy_teardrops no)
	)
	(paper "A4")
	(title_block
		(title "03242023_DA0F0TMBIJ0_F0T_Motherboard_J_brd_V01_OCP.brd")
		(comment 1 "Grand Teton / footprints 5160-5161 of 6105")
	)
	(layers
		(0 "F.Cu" signal "TOP")
		(4 "In1.Cu" signal "GND")
		(6 "In2.Cu" signal "IN1")
		(8 "In3.Cu" signal "GND1")
		(10 "In4.Cu" signal "IN2")
		(12 "In5.Cu" signal "GND2")
		(14 "In6.Cu" signal "IN3")
		(16 "In7.Cu" signal "GND3")
		(18 "In8.Cu" signal "VCC")
		(20 "In9.Cu" signal "VCC1")
		(22 "In10.Cu" signal "GND4")
		(24 "In11.Cu" signal "IN4")
		(26 "In12.Cu" signal "GND5")
		(28 "In13.Cu" signal "IN5")
		(30 "In14.Cu" signal "GND6")
		(32 "In15.Cu" signal "IN6")
		(34 "In16.Cu" signal "GND7")
		(2 "B.Cu" signal "BOTTOM")
		(9 "F.Adhes" user "F.Adhesive")
		(11 "B.Adhes" user "B.Adhesive")
		(13 "F.Paste" user "Package Geometry/Pastemask Top")
		(15 "B.Paste" user "Package Geometry/Pastemask Bottom")
		(5 "F.SilkS" user "Ref Des/Silkscreen Top")
		(7 "B.SilkS" user "Ref Des/Silkscreen Bottom")
		(1 "F.Mask" user "Board Geometry/Soldermask Top")
		(3 "B.Mask" user "Board Geometry/Soldermask Bottom")
		(17 "Dwgs.User" user "User.Drawings")
		(19 "Cmts.User" user "User.Comments")
		(21 "Eco1.User" user "User.Eco1")
		(23 "Eco2.User" user "User.Eco2")
		(25 "Edge.Cuts" user "Board Geometry/Outline")
		(27 "Margin" user)
		(31 "F.CrtYd" user "Package Geometry/Place Bound Top")
		(29 "B.CrtYd" user "Package Geometry/Place Bound Bottom")
		(35 "F.Fab" user "Ref Des/Assembly Top")
		(33 "B.Fab" user "Ref Des/Assembly Bottom")
	)
	(footprint ""
		(layer "B.Cu")
		(at 297.44416 -50.226468)
		(property "Reference" "C1187"
			(at 0 0 0)
			(layer "B.SilkS")
			(hide yes)
			(effects
				(font
					(size 1.27 1.27)
				)
				(justify mirror)
			)
		)
		(property "Value" ""
			(at 0 0 0)
			(layer "B.Fab")
			(effects
				(font
					(size 1.27 1.27)
				)
				(justify mirror)
			)
		)
		(duplicate_pad_numbers_are_jumpers no)
		(fp_line
			(start -1.2954 -0.5842)
			(end -1.2954 0.5842)
			(stroke
				(width 0.1524)
				(type default)
			)
			(layer "B.SilkS")
		)
		(fp_line
			(start -1.2954 0.5842)
			(end 1.2954 0.5842)
			(stroke
				(width 0.1524)
				(type default)
			)
			(layer "B.SilkS")
		)
		(fp_line
			(start 0 -0.5842)
			(end 0 0.5842)
			(stroke
				(width 0.1524)
				(type default)
			)
			(layer "B.SilkS")
		)
		(fp_line
			(start 1.2954 -0.5842)
			(end -1.2954 -0.5842)
			(stroke
				(width 0.1524)
				(type default)
			)
			(layer "B.SilkS")
		)
		(fp_line
			(start 1.2954 0.5842)
			(end 1.2954 -0.5842)
			(stroke
				(width 0.1524)
				(type default)
			)
			(layer "B.SilkS")
		)
		(fp_line
			(start -1.1938 -0.4064)
			(end -1.1938 0.4064)
			(stroke
				(width 0.1)
				(type default)
			)
			(layer "B.Fab")
		)
		(fp_line
			(start -1.1938 0.4064)
			(end -0.8636 0.4064)
			(stroke
				(width 0.1)
				(type default)
			)
			(layer "B.Fab")
		)
		(fp_line
			(start -0.8636 -0.4572)
			(end -0.8636 -0.4064)
			(stroke
				(width 0.1)
				(type default)
			)
			(layer "B.Fab")
		)
		(fp_line
			(start -0.8636 -0.4064)
			(end -1.1938 -0.4064)
			(stroke
				(width 0.1)
				(type default)
			)
			(layer "B.Fab")
		)
		(fp_line
			(start -0.8636 0.4064)
			(end -0.8636 0.4572)
			(stroke
				(width 0.1)
				(type default)
			)
			(layer "B.Fab")
		)
		(fp_line
			(start -0.8636 0.4572)
			(end 0.8636 0.4572)
			(stroke
				(width 0.1)
				(type default)
			)
			(layer "B.Fab")
		)
		(fp_line
			(start 0.8636 -0.4572)
			(end -0.8636 -0.4572)
			(stroke
				(width 0.1)
				(type default)
			)
			(layer "B.Fab")
		)
		(fp_line
			(start 0.8636 -0.4064)
			(end 0.8636 -0.4572)
			(stroke
				(width 0.1)
				(type default)
			)
			(layer "B.Fab")
		)
		(fp_line
			(start 0.8636 0.4064)
			(end 1.1938 0.4064)
			(stroke
				(width 0.1)
				(type default)
			)
			(layer "B.Fab")
		)
		(fp_line
			(start 0.8636 0.4572)
			(end 0.8636 0.4064)
			(stroke
				(width 0.1)
				(type default)
			)
			(layer "B.Fab")
		)
		(fp_line
			(start 1.1938 -0.4064)
			(end 0.8636 -0.4064)
			(stroke
				(width 0.1)
				(type default)
			)
			(layer "B.Fab")
		)
		(fp_line
			(start 1.1938 0.4064)
			(end 1.1938 -0.4064)
			(stroke
				(width 0.1)
				(type default)
			)
			(layer "B.Fab")
		)
		(pad "1" smd rect
			(at 0.7366 0 270)
			(size 0.7112 0.8128)
			(layers "B.Cu" "B.Mask" "B.Paste")
			(net "P1V05_PCH_AUX")
		)
		(pad "2" smd rect
			(at -0.7366 0 270)
			(size 0.7112 0.8128)
			(layers "B.Cu" "B.Mask" "B.Paste")
			(net "GND")
		)
	)
	(footprint ""
		(layer "B.Cu")
		(at 319.58153 -32.470598 -90)
		(property "Reference" "R1744"
			(at 0 0 90)
			(layer "B.SilkS")
			(hide yes)
			(effects
				(font
					(size 1.27 1.27)
				)
				(justify mirror)
			)
		)
		(property "Value" ""
			(at 0 0 90)
			(layer "B.Fab")
			(effects
				(font
					(size 1.27 1.27)
				)
				(justify mirror)
			)
		)
		(duplicate_pad_numbers_are_jumpers no)
		(fp_line
			(start -0.7874 0.4064)
			(end 0.7874 0.4064)
			(stroke
				(width 0.1524)
				(type default)
			)
			(layer "B.SilkS")
		)
		(fp_line
			(start 0.7874 0.4064)
			(end 0.7874 -0.4064)
			(stroke
				(width 0.1524)
				(type default)
			)
			(layer "B.SilkS")
		)
		(fp_line
			(start -0.7874 -0.4064)
			(end -0.7874 0.4064)
			(stroke
				(width 0.1524)
				(type default)
			)
			(layer "B.SilkS")
		)
		(fp_line
			(start 0.7874 -0.4064)
			(end -0.7874 -0.4064)
			(stroke
				(width 0.1524)
				(type default)
			)
			(layer "B.SilkS")
		)
		(fp_line
			(start -0.67945 0.3048)
			(end -0.120396 0.3048)
			(stroke
				(width 0.1)
				(type default)
			)
			(layer "B.Fab")
		)
		(fp_line
			(start -0.120396 0.3048)
			(end -0.120396 0.2794)
			(stroke
				(width 0.1)
				(type default)
			)
			(layer "B.Fab")
		)
		(fp_line
			(start 0.12065 0.3048)
			(end 0.67945 0.3048)
			(stroke
				(width 0.1)
				(type default)
			)
			(layer "B.Fab")
		)
		(fp_line
			(start 0.67945 0.3048)
			(end 0.67945 -0.305054)
			(stroke
				(width 0.1)
				(type default)
			)
			(layer "B.Fab")
		)
		(fp_line
			(start -0.120396 0.2794)
			(end 0.12065 0.2794)
			(stroke
				(width 0.1)
				(type default)
			)
			(layer "B.Fab")
		)
		(fp_line
			(start 0.12065 0.2794)
			(end 0.12065 0.3048)
			(stroke
				(width 0.1)
				(type default)
			)
			(layer "B.Fab")
		)
		(fp_line
			(start -0.12065 -0.2794)
			(end -0.12065 -0.3048)
			(stroke
				(width 0.1)
				(type default)
			)
			(layer "B.Fab")
		)
		(fp_line
			(start 0.12065 -0.2794)
			(end -0.12065 -0.2794)
			(stroke
				(width 0.1)
				(type default)
			)
			(layer "B.Fab")
		)
		(fp_line
			(start -0.67945 -0.3048)
			(end -0.67945 0.3048)
			(stroke
				(width 0.1)
				(type default)
			)
			(layer "B.Fab")
		)
		(fp_line
			(start -0.12065 -0.3048)
			(end -0.67945 -0.3048)
			(stroke
				(width 0.1)
				(type default)
			)
			(layer "B.Fab")
		)
		(fp_line
			(start 0.12065 -0.305054)
			(end 0.12065 -0.2794)
			(stroke
				(width 0.1)
				(type default)
			)
			(layer "B.Fab")
		)
		(fp_line
			(start 0.67945 -0.305054)
			(end 0.12065 -0.305054)
			(stroke
				(width 0.1)
				(type default)
			)
			(layer "B.Fab")
		)
		(pad "1" smd circle
			(at 0.40005 0 90)
			(size 0 0)
			(layers "B.Cu" "B.Mask" "B.Paste")
			(net "FM_BMC_PWRBTN_OUT_N")
		)
		(pad "2" smd circle
			(at -0.40005 0 90)
			(size 0 0)
			(layers "B.Cu" "B.Mask" "B.Paste")
			(net "FM_BMC_PWRBTN_N")
		)
	)
)
